# BASEBOARD_FAB2 (Tioga Pass) — schematic netlist excerpt (pin names and nets, part order shuffled) for the footprints in the layout excerpt that follows; sources: Cadence DE-HDL packaged netlist, KiCad conversion of Wiwynn_Tioga_Pass_MB.brd

R2P17  RES  4.75K 1% CHIP  pkg 0402  page 134 : A = P3V3_STBY ; B = FM_PCH_BMC_THERMTRIP_N
C5D25  CAP_A  22.0UF 4V 20% X6S  pkg 0603V  page 42 : A = PVCCIN_CPU0 ; B = GND
C22W8  SC22U16V5MX-4-GP  20%  pkg SMD-BCG5  page 241 : \1\ = VR_FET_SW_P5V_STBY_PVIN ; \2\ = GND

(kicad_pcb
	(version 20260206)
	(generator "pcbnew")
	(generator_version "10.0")
	(general
		(thickness 1.6)
		(legacy_teardrops no)
	)
	(paper "A4")
	(title_block
		(title "Wiwynn_Tioga_Pass_MB.brd")
		(comment 1 "Tioga Pass / footprints 2025-2027 of 4770")
	)
	(layers
		(0 "F.Cu" signal "TOP")
		(4 "In1.Cu" signal "L2GND")
		(6 "In2.Cu" signal "L3")
		(8 "In3.Cu" signal "L4GND")
		(10 "In4.Cu" signal "L5")
		(12 "In5.Cu" signal "L6GND")
		(14 "In6.Cu" signal "L7VCC")
		(16 "In7.Cu" signal "L8VCC")
		(18 "In8.Cu" signal "L9GND")
		(20 "In9.Cu" signal "L10")
		(22 "In10.Cu" signal "L11GND")
		(24 "In11.Cu" signal "L12")
		(26 "In12.Cu" signal "L13GND")
		(2 "B.Cu" signal "BOTTOM")
		(9 "F.Adhes" user "F.Adhesive")
		(11 "B.Adhes" user "B.Adhesive")
		(13 "F.Paste" user "Package Geometry/Pastemask Top")
		(15 "B.Paste" user "Package Geometry/Pastemask Bottom")
		(5 "F.SilkS" user "Ref Des/Silkscreen Top")
		(7 "B.SilkS" user "Ref Des/Silkscreen Bottom")
		(1 "F.Mask" user "Board Geometry/Soldermask Top")
		(3 "B.Mask" user "Board Geometry/Soldermask Bottom")
		(17 "Dwgs.User" user "User.Drawings")
		(19 "Cmts.User" user "User.Comments")
		(21 "Eco1.User" user "User.Eco1")
		(23 "Eco2.User" user "User.Eco2")
		(25 "Edge.Cuts" user "Board Geometry/Outline")
		(27 "Margin" user)
		(31 "F.CrtYd" user "Package Geometry/Place Bound Top")
		(29 "B.CrtYd" user "Package Geometry/Place Bound Bottom")
		(35 "F.Fab" user "Ref Des/Assembly Top")
		(33 "B.Fab" user "Ref Des/Assembly Bottom")
	)
	(footprint ""
		(layer "F.Cu")
		(at 398.8689 -87.4649 -90)
		(property "Reference" "R2P17"
			(at 0 0 270)
			(layer "F.SilkS")
			(hide yes)
			(effects
				(font
					(size 1.27 1.27)
				)
			)
		)
		(property "Value" ""
			(at 0 0 270)
			(layer "F.Fab")
			(effects
				(font
					(size 1.27 1.27)
				)
			)
		)
		(duplicate_pad_numbers_are_jumpers no)
		(fp_poly
			(pts
				(xy -0.2794 -0.1016) (xy 0.2794 -0.1016) (xy 0.2794 0.9906) (xy -0.2794 0.9906)
			)
			(stroke
				(width 0)
				(type default)
			)
			(fill no)
			(layer "F.CrtYd")
		)
		(fp_line
			(start -0.2794 0.9906)
			(end 0.2794 0.9906)
			(stroke
				(width 0.1)
				(type default)
			)
			(layer "F.Fab")
		)
		(fp_line
			(start 0.2794 0.9906)
			(end 0.2794 -0.1016)
			(stroke
				(width 0.1)
				(type default)
			)
			(layer "F.Fab")
		)
		(fp_line
			(start -0.2794 -0.1016)
			(end -0.2794 0.9906)
			(stroke
				(width 0.1)
				(type default)
			)
			(layer "F.Fab")
		)
		(fp_line
			(start 0.2794 -0.1016)
			(end -0.2794 -0.1016)
			(stroke
				(width 0.1)
				(type default)
			)
			(layer "F.Fab")
		)
		(pad "1" smd rect
			(at 0 0 270)
			(size 0.508 0.508)
			(layers "F.Cu" "F.Mask" "F.Paste")
			(net "P3V3_STBY")
		)
		(pad "2" smd rect
			(at 0 0.889 270)
			(size 0.508 0.508)
			(layers "F.Cu" "F.Mask" "F.Paste")
			(net "FM_PCH_BMC_THERMTRIP_N")
		)
		(zone
			(layer "F.Cu")
			(hatch none 0.5)
			(connect_pads
				(clearance 0)
			)
			(min_thickness 0.25)
			(keepout
				(tracks not_allowed)
				(vias allowed)
				(pads allowed)
				(copperpour not_allowed)
				(footprints allowed)
			)
			(placement
				(enabled no)
				(sheetname "")
			)
			(fill
				(thermal_gap 0.5)
				(thermal_bridge_width 0.5)
				(island_removal_mode 0)
			)
			(polygon
				(pts
					(xy 398.2339 -87.7189) (xy 398.2339 -87.2109) (xy 398.6149 -87.2109) (xy 398.6149 -87.7189)
				)
			)
		)
		(zone
			(layer "F.Cu")
			(hatch none 0.5)
			(connect_pads
				(clearance 0)
			)
			(min_thickness 0.25)
			(keepout
				(tracks allowed)
				(vias not_allowed)
				(pads allowed)
				(copperpour not_allowed)
				(footprints allowed)
			)
			(placement
				(enabled no)
				(sheetname "")
			)
			(fill
				(thermal_gap 0.5)
				(thermal_bridge_width 0.5)
				(island_removal_mode 0)
			)
			(polygon
				(pts
					(xy 398.6149 -87.7189) (xy 398.6149 -87.2109) (xy 398.2339 -87.2109) (xy 398.2339 -87.7189)
				)
			)
		)
	)
	(footprint ""
		(layer "F.Cu")
		(at 259.452872 -77.636116)
		(property "Reference" "C5D25"
			(at 0 0 0)
			(layer "F.SilkS")
			(hide yes)
			(effects
				(font
					(size 1.27 1.27)
				)
			)
		)
		(property "Value" ""
			(at 0 0 0)
			(layer "F.Fab")
			(effects
				(font
					(size 1.27 1.27)
				)
			)
		)
		(duplicate_pad_numbers_are_jumpers no)
		(fp_poly
			(pts
				(xy -0.4953 -0.2032) (xy 0.4953 -0.2032) (xy 0.4953 1.6002) (xy -0.4953 1.6002)
			)
			(stroke
				(width 0)
				(type default)
			)
			(fill no)
			(layer "F.CrtYd")
		)
		(fp_line
			(start -0.4953 -0.2032)
			(end 0.4953 -0.2032)
			(stroke
				(width 0.1)
				(type default)
			)
			(layer "F.Fab")
		)
		(fp_line
			(start -0.4953 1.6002)
			(end -0.4953 -0.2032)
			(stroke
				(width 0.1)
				(type default)
			)
			(layer "F.Fab")
		)
		(fp_line
			(start 0.4953 -0.2032)
			(end 0.4953 1.6002)
			(stroke
				(width 0.1)
				(type default)
			)
			(layer "F.Fab")
		)
		(fp_line
			(start 0.4953 1.6002)
			(end -0.4953 1.6002)
			(stroke
				(width 0.1)
				(type default)
			)
			(layer "F.Fab")
		)
		(pad "1" smd rect
			(at 0 0)
			(size 0.762 0.889)
			(layers "F.Cu" "F.Mask" "F.Paste")
			(net "PVCCIN_CPU0")
		)
		(pad "2" smd rect
			(at 0 1.397)
			(size 0.762 0.889)
			(layers "F.Cu" "F.Mask" "F.Paste")
			(net "GND")
		)
		(zone
			(layer "F.Cu")
			(hatch none 0.5)
			(connect_pads
				(clearance 0)
			)
			(min_thickness 0.25)
			(keepout
				(tracks not_allowed)
				(vias allowed)
				(pads allowed)
				(copperpour not_allowed)
				(footprints allowed)
			)
			(placement
				(enabled no)
				(sheetname "")
			)
			(fill
				(thermal_gap 0.5)
				(thermal_bridge_width 0.5)
				(island_removal_mode 0)
			)
			(polygon
				(pts
					(xy 259.071872 -77.191616) (xy 259.833872 -77.191616) (xy 259.833872 -76.683616) (xy 259.071872 -76.683616)
				)
			)
		)
	)
	(footprint ""
		(layer "F.Cu")
		(at 387.8326 -65.3034)
		(property "Reference" "C22W8"
			(at 0 0 0)
			(layer "F.SilkS")
			(hide yes)
			(effects
				(font
					(size 1.27 1.27)
				)
			)
		)
		(property "Value" "*"
			(at -0.0762 -6.2357 0)
			(unlocked yes)
			(layer "F.Fab")
			(hide yes)
			(effects
				(font
					(size 1.27 1.016)
					(thickness 0.1524)
				)
			)
		)
		(property "Device Type" "SC22U16V5MX-4-GP_SMD-BCG5-SC22A"
			(at -0.0762 -8.2677 0)
			(unlocked yes)
			(layer "F.Fab")
			(hide yes)
			(effects
				(font
					(size 1.27 1.016)
					(thickness 0.1524)
				)
			)
		)
		(duplicate_pad_numbers_are_jumpers no)
		(fp_line
			(start 0.635 0)
			(end -0.635 0)
			(stroke
				(width 0.508)
				(type default)
			)
			(layer "F.SilkS")
		)
		(fp_rect
			(start -0.9652 1.778)
			(end 0.9652 -1.778)
			(stroke
				(width 0)
				(type default)
			)
			(fill no)
			(layer "F.CrtYd")
		)
		(fp_poly
			(pts
				(xy -0.9652 -1.778) (xy 0.9652 -1.778) (xy 0.9652 1.778) (xy -0.9652 1.778)
			)
			(stroke
				(width 0)
				(type default)
			)
			(fill no)
			(layer "F.Fab")
		)
		(pad "1" smd rect
			(at 0 -0.9652)
			(size 1.397 1.143)
			(layers "F.Cu" "F.Mask" "F.Paste")
			(net "VR_FET_SW_P5V_STBY_PVIN")
		)
		(pad "2" smd rect
			(at 0 0.9652)
			(size 1.397 1.143)
			(layers "F.Cu" "F.Mask" "F.Paste")
			(net "GND")
		)
	)
)
